(kicad_pcb
	(version 20241229)
	(generator "pcbnew")
	(generator_version "9.0")
	(general
		(thickness 1.294)
		(legacy_teardrops no)
	)
	(paper "A3")
	(title_block
		(title "Kintex 410T devboard")
		(date "2024-04-03")
		(rev "1.1.2")
		(comment 9 "footprints 870-875 of 975")
	)
	(layers
		(0 "F.Cu" mixed)
		(4 "In1.Cu" power)
		(6 "In2.Cu" power)
		(8 "In3.Cu" mixed)
		(10 "In4.Cu" power)
		(12 "In5.Cu" mixed)
		(14 "In6.Cu" power)
		(16 "In7.Cu" mixed)
		(18 "In8.Cu" power)
		(2 "B.Cu" mixed)
		(9 "F.Adhes" user "F.Adhesive")
		(11 "B.Adhes" user "B.Adhesive")
		(13 "F.Paste" user)
		(15 "B.Paste" user)
		(5 "F.SilkS" user "F.Silkscreen")
		(7 "B.SilkS" user "B.Silkscreen")
		(1 "F.Mask" user)
		(3 "B.Mask" user)
		(17 "Dwgs.User" user "User.Drawings")
		(19 "Cmts.User" user "User.Comments")
		(21 "Eco1.User" user "User.Eco1")
		(23 "Eco2.User" user "User.Eco2")
		(25 "Edge.Cuts" user)
		(27 "Margin" user)
		(31 "F.CrtYd" user "F.Courtyard")
		(29 "B.CrtYd" user "B.Courtyard")
		(35 "F.Fab" user)
		(33 "B.Fab" user)
	)
	(footprint "antmicro-footprints:C_0603_1608Metric"
		(layer "B.Cu")
		(at 200 128.775 -90)
		(descr "Capacitor SMD 0603")
		(tags "capacitor 0603")
		(property "Reference" "C376"
			(at -31.05 -25.75 90)
			(layer "B.SilkS")
			(effects
				(font
					(size 0.7 0.7)
					(thickness 0.15)
				)
				(justify left bottom mirror)
			)
		)
		(property "Value" "C_47u_0603"
			(at 0 -1.6 90)
			(layer "B.Fab")
			(effects
				(font
					(size 0.7 0.7)
					(thickness 0.15)
				)
				(justify left bottom mirror)
			)
		)
		(property "Description" "SMD Multilayer Ceramic Capacitor, 47 µF, 6.3 V, 0603 [1608 Metric], ± 20%, X5R, GRM Series"
			(at 0 0 270)
			(layer "F.Fab")
			(hide yes)
			(effects
				(font
					(size 1.27 1.27)
					(thickness 0.15)
				)
			)
		)
		(property "Author" "Antmicro"
			(at 71.225 328.775 0)
			(layer "B.Fab")
			(hide yes)
			(effects
				(font
					(size 1 1)
					(thickness 0.15)
				)
				(justify mirror)
			)
		)
		(property "Dielectric" ""
			(at 71.225 328.775 0)
			(layer "B.Fab")
			(hide yes)
			(effects
				(font
					(size 1 1)
					(thickness 0.15)
				)
				(justify mirror)
			)
		)
		(property "License" "Apache-2.0"
			(at 71.225 328.775 0)
			(layer "B.Fab")
			(hide yes)
			(effects
				(font
					(size 1 1)
					(thickness 0.15)
				)
				(justify mirror)
			)
		)
		(property "MPN" "GRM188R60J476ME15D"
			(at 71.225 328.775 0)
			(layer "B.Fab")
			(hide yes)
			(effects
				(font
					(size 1 1)
					(thickness 0.15)
				)
				(justify mirror)
			)
		)
		(property "Manufacturer" "Murata"
			(at 71.225 328.775 0)
			(layer "B.Fab")
			(hide yes)
			(effects
				(font
					(size 1 1)
					(thickness 0.15)
				)
				(justify mirror)
			)
		)
		(property "Val" "47u"
			(at 71.225 328.775 0)
			(layer "B.Fab")
			(hide yes)
			(effects
				(font
					(size 1 1)
					(thickness 0.15)
				)
				(justify mirror)
			)
		)
		(property "Voltage" ""
			(at 71.225 328.775 0)
			(layer "B.Fab")
			(hide yes)
			(effects
				(font
					(size 1 1)
					(thickness 0.15)
				)
				(justify mirror)
			)
		)
		(sheetname "FPGA supply")
		(sheetfile "fpga-supply.kicad_sch")
		(attr smd)
		(fp_line
			(start -0.15 0.4)
			(end 0.15 0.4)
			(stroke
				(width 0.15)
				(type solid)
			)
			(layer "B.SilkS")
		)
		(fp_line
			(start -0.15 -0.4)
			(end 0.15 -0.4)
			(stroke
				(width 0.15)
				(type solid)
			)
			(layer "B.SilkS")
		)
		(fp_rect
			(start -1.25 0.65)
			(end 1.25 -0.65)
			(stroke
				(width 0.05)
				(type solid)
			)
			(fill no)
			(layer "B.CrtYd")
		)
		(fp_rect
			(start -0.8 0.4)
			(end 0.8 -0.4)
			(stroke
				(width 0.15)
				(type solid)
			)
			(fill no)
			(layer "B.Fab")
		)
		(pad "1" smd roundrect
			(at -0.7 0 270)
			(size 0.8 1)
			(layers "B.Cu" "B.Mask" "B.Paste")
			(roundrect_rratio 0.2)
			(net 1 "GND")
			(pintype "passive")
		)
		(pad "2" smd roundrect
			(at 0.7 0 270)
			(size 0.8 1)
			(layers "B.Cu" "B.Mask" "B.Paste")
			(roundrect_rratio 0.2)
			(net 650 "+1V0")
			(pintype "passive")
		)
	)
	(footprint "antmicro-footprints:C_0402_1005Metric"
		(layer "B.Cu")
		(at 190.275 136.05 -90)
		(descr "Capacitor SMD 0402")
		(tags "capacitor SMD 0402")
		(property "Reference" "C10"
			(at -30.025 -21.925 90)
			(layer "B.SilkS")
			(effects
				(font
					(size 0.7 0.7)
					(thickness 0.15)
				)
				(justify left bottom mirror)
			)
		)
		(property "Value" "C_100n_0402"
			(at 0 -1.169 90)
			(layer "B.Fab")
			(effects
				(font
					(size 0.7 0.7)
					(thickness 0.15)
				)
				(justify left bottom mirror)
			)
		)
		(property "Description" "SMD Multilayer Ceramic Capacitor, 0.1 µF, 50 V, 0402 [1005 Metric], ± 10%, X5R, GRM Series"
			(at 0 0 270)
			(layer "F.Fab")
			(hide yes)
			(effects
				(font
					(size 1.27 1.27)
					(thickness 0.15)
				)
			)
		)
		(property "Author" "Antmicro"
			(at 54.225 326.325 0)
			(layer "B.Fab")
			(hide yes)
			(effects
				(font
					(size 1 1)
					(thickness 0.15)
				)
				(justify mirror)
			)
		)
		(property "Dielectric" "X5R"
			(at 54.225 326.325 0)
			(layer "B.Fab")
			(hide yes)
			(effects
				(font
					(size 1 1)
					(thickness 0.15)
				)
				(justify mirror)
			)
		)
		(property "License" "Apache-2.0"
			(at 54.225 326.325 0)
			(layer "B.Fab")
			(hide yes)
			(effects
				(font
					(size 1 1)
					(thickness 0.15)
				)
				(justify mirror)
			)
		)
		(property "MPN" "GRM155R61H104KE14D"
			(at 54.225 326.325 0)
			(layer "B.Fab")
			(hide yes)
			(effects
				(font
					(size 1 1)
					(thickness 0.15)
				)
				(justify mirror)
			)
		)
		(property "Manufacturer" "Murata"
			(at 54.225 326.325 0)
			(layer "B.Fab")
			(hide yes)
			(effects
				(font
					(size 1 1)
					(thickness 0.15)
				)
				(justify mirror)
			)
		)
		(property "Val" "100n"
			(at 54.225 326.325 0)
			(layer "B.Fab")
			(hide yes)
			(effects
				(font
					(size 1 1)
					(thickness 0.15)
				)
				(justify mirror)
			)
		)
		(property "Voltage" "50V"
			(at 54.225 326.325 0)
			(layer "B.Fab")
			(hide yes)
			(effects
				(font
					(size 1 1)
					(thickness 0.15)
				)
				(justify mirror)
			)
		)
		(sheetname "FPGA Config")
		(sheetfile "fpga-config.kicad_sch")
		(attr smd)
		(fp_rect
			(start -0.925 0.47)
			(end 0.925 -0.47)
			(stroke
				(width 0.05)
				(type default)
			)
			(fill no)
			(layer "B.CrtYd")
		)
		(fp_line
			(start -0.494 0.25)
			(end 0.504 0.25)
			(stroke
				(width 0.15)
				(type solid)
			)
			(layer "B.Fab")
		)
		(fp_line
			(start 0.504 0.25)
			(end 0.504 -0.248)
			(stroke
				(width 0.15)
				(type solid)
			)
			(layer "B.Fab")
		)
		(fp_line
			(start -0.494 -0.248)
			(end -0.494 0.25)
			(stroke
				(width 0.15)
				(type solid)
			)
			(layer "B.Fab")
		)
		(fp_line
			(start 0.504 -0.248)
			(end -0.494 -0.248)
			(stroke
				(width 0.15)
				(type solid)
			)
			(layer "B.Fab")
		)
		(pad "1" smd roundrect
			(at -0.48 0 270)
			(size 0.59 0.64)
			(layers "B.Cu" "B.Mask" "B.Paste")
			(roundrect_rratio 0.25)
			(net 1 "GND")
			(pintype "passive")
		)
		(pad "2" smd roundrect
			(at 0.48 0 270)
			(size 0.59 0.64)
			(layers "B.Cu" "B.Mask" "B.Paste")
			(roundrect_rratio 0.25)
			(net 24 "+3V3")
			(pintype "passive")
		)
	)
	(footprint "antmicro-footprints:Coax_Conn_U.FL"
		(layer "B.Cu")
		(at 220.44 136.3 90)
		(descr "https://media.digikey.com/pdf/Data%20Sheets/Hirose%20PDFs/UFL%20Series.pdf")
		(property "Reference" "J3"
			(at -2.16 2.19 270)
			(layer "B.SilkS")
			(effects
				(font
					(size 0.7 0.7)
					(thickness 0.15)
				)
				(justify left bottom mirror)
			)
		)
		(property "Value" "U_FL-R-SMT-1"
			(at -4.13 -2.52 270)
			(layer "B.Fab")
			(effects
				(font
					(size 0.7 0.7)
					(thickness 0.15)
				)
				(justify left bottom mirror)
			)
		)
		(property "Description" "U.FL (UMCC) Connector Receptacle, Male Pin 50Ohm Surface Mount Solder"
			(at 0 0 90)
			(layer "F.Fab")
			(hide yes)
			(effects
				(font
					(size 1.27 1.27)
					(thickness 0.15)
				)
			)
		)
		(property "Author" "Antmicro"
			(at 356.74 -84.14 0)
			(layer "B.Fab")
			(hide yes)
			(effects
				(font
					(size 1 1)
					(thickness 0.15)
				)
				(justify mirror)
			)
		)
		(property "License" "Apache-2.0"
			(at 356.74 -84.14 0)
			(layer "B.Fab")
			(hide yes)
			(effects
				(font
					(size 1 1)
					(thickness 0.15)
				)
				(justify mirror)
			)
		)
		(property "MPN" "U.FL-R-SMT-1(10)"
			(at 356.74 -84.14 0)
			(layer "B.Fab")
			(hide yes)
			(effects
				(font
					(size 1 1)
					(thickness 0.15)
				)
				(justify mirror)
			)
		)
		(property "Manufacturer" "Hirose Electric"
			(at 356.74 -84.14 0)
			(layer "B.Fab")
			(hide yes)
			(effects
				(font
					(size 1 1)
					(thickness 0.15)
				)
				(justify mirror)
			)
		)
		(sheetname "Clocks")
		(sheetfile "clocks.kicad_sch")
		(attr smd)
		(fp_line
			(start 1.588 -1.648)
			(end 1.088 -1.648)
			(stroke
				(width 0.15)
				(type solid)
			)
			(layer "B.SilkS")
		)
		(fp_line
			(start 1.588 -1.648)
			(end 1.588 -1.325)
			(stroke
				(width 0.15)
				(type solid)
			)
			(layer "B.SilkS")
		)
		(fp_line
			(start -1.613 -1.648)
			(end -1.113 -1.648)
			(stroke
				(width 0.15)
				(type solid)
			)
			(layer "B.SilkS")
		)
		(fp_line
			(start -1.613 -1.648)
			(end -1.613 -1.325)
			(stroke
				(width 0.15)
				(type solid)
			)
			(layer "B.SilkS")
		)
		(fp_line
			(start 1.588 1.651)
			(end 1.588 1.325)
			(stroke
				(width 0.15)
				(type solid)
			)
			(layer "B.SilkS")
		)
		(fp_line
			(start 1.588 1.651)
			(end 1.088 1.651)
			(stroke
				(width 0.15)
				(type solid)
			)
			(layer "B.SilkS")
		)
		(fp_line
			(start -1.613 1.651)
			(end -1.613 1.325)
			(stroke
				(width 0.15)
				(type solid)
			)
			(layer "B.SilkS")
		)
		(fp_line
			(start -1.613 1.651)
			(end -1.113 1.651)
			(stroke
				(width 0.15)
				(type solid)
			)
			(layer "B.SilkS")
		)
		(fp_rect
			(start -2 2.051)
			(end 1.999 -2.05)
			(stroke
				(width 0.05)
				(type solid)
			)
			(fill no)
			(layer "B.CrtYd")
		)
		(fp_line
			(start 1.487 -1.55)
			(end 1.487 1.551)
			(stroke
				(width 0.15)
				(type solid)
			)
			(layer "B.Fab")
		)
		(fp_line
			(start -1.512 -1.55)
			(end 1.487 -1.55)
			(stroke
				(width 0.15)
				(type solid)
			)
			(layer "B.Fab")
		)
		(fp_line
			(start -1.512 -1.55)
			(end -1.512 1.551)
			(stroke
				(width 0.15)
				(type solid)
			)
			(layer "B.Fab")
		)
		(fp_line
			(start -1.512 1.551)
			(end 1.487 1.551)
			(stroke
				(width 0.15)
				(type solid)
			)
			(layer "B.Fab")
		)
		(pad "1" smd rect
			(at -0.012 -1.499 90)
			(size 1 1.05)
			(layers "B.Cu" "B.Mask" "B.Paste")
			(net 1244 "/PLL.CLK0")
			(pintype "passive")
		)
		(pad "SH1" smd rect
			(at 1.463 0 90)
			(size 1.05 2.2)
			(layers "B.Cu" "B.Mask" "B.Paste")
			(net 1 "GND")
			(pintype "passive")
		)
		(pad "SH2" smd rect
			(at -1.488 0 90)
			(size 1.05 2.2)
			(layers "B.Cu" "B.Mask" "B.Paste")
			(net 1 "GND")
			(pintype "passive")
		)
		(zone
			(net 0)
			(net_name "")
			(layer "B.Cu")
			(hatch edge 0.508)
			(connect_pads
				(clearance 0)
			)
			(min_thickness 0.254)
			(filled_areas_thickness no)
			(keepout
				(tracks not_allowed)
				(vias not_allowed)
				(pads not_allowed)
				(copperpour not_allowed)
				(footprints not_allowed)
			)
			(placement
				(enabled no)
				(sheetname "")
			)
			(fill
				(thermal_gap 0.508)
				(thermal_bridge_width 0.508)
			)
			(polygon
				(pts
					(xy 219.48 135.37) (xy 219.48 137.25) (xy 221.54 137.25) (xy 221.54 135.37)
				)
			)
		)
	)
	(footprint "antmicro-footprints:R_0402_1005Metric"
		(layer "B.Cu")
		(at 202.2 92.7 -90)
		(descr "Resistor SMD 0402")
		(tags "resistor SMD 0402")
		(property "Reference" "R215"
			(at -0.9 -2.4 90)
			(layer "B.SilkS")
			(effects
				(font
					(size 0.7 0.7)
					(thickness 0.15)
				)
				(justify left bottom mirror)
			)
		)
		(property "Value" "R_2k2_0402"
			(at 0 -1.4 90)
			(layer "B.Fab")
			(effects
				(font
					(size 0.7 0.7)
					(thickness 0.15)
				)
				(justify left bottom mirror)
			)
		)
		(property "Description" "SMD Chip Resistor, 2.2 kohm, ± 1%, 62.5 mW, 0402 [1005 Metric], Thick Film, General Purpose"
			(at 0 0 270)
			(layer "F.Fab")
			(hide yes)
			(effects
				(font
					(size 1.27 1.27)
					(thickness 0.15)
				)
			)
		)
		(property "Author" "Antmicro"
			(at 109.5 294.9 0)
			(layer "B.Fab")
			(hide yes)
			(effects
				(font
					(size 1 1)
					(thickness 0.15)
				)
				(justify mirror)
			)
		)
		(property "DNP" "DNP"
			(at 109.5 294.9 0)
			(layer "B.Fab")
			(hide yes)
			(effects
				(font
					(size 1 1)
					(thickness 0.15)
				)
				(justify mirror)
			)
		)
		(property "License" "Apache-2.0"
			(at 109.5 294.9 0)
			(layer "B.Fab")
			(hide yes)
			(effects
				(font
					(size 1 1)
					(thickness 0.15)
				)
				(justify mirror)
			)
		)
		(property "MPN" "CR0402-FX-2201GLF"
			(at 109.5 294.9 0)
			(layer "B.Fab")
			(hide yes)
			(effects
				(font
					(size 1 1)
					(thickness 0.15)
				)
				(justify mirror)
			)
		)
		(property "Manufacturer" "Bourns"
			(at 109.5 294.9 0)
			(layer "B.Fab")
			(hide yes)
			(effects
				(font
					(size 1 1)
					(thickness 0.15)
				)
				(justify mirror)
			)
		)
		(property "Tolerance" "1%"
			(at 109.5 294.9 0)
			(layer "B.Fab")
			(hide yes)
			(effects
				(font
					(size 1 1)
					(thickness 0.15)
				)
				(justify mirror)
			)
		)
		(property "Val" "2k2"
			(at 109.5 294.9 0)
			(layer "B.Fab")
			(hide yes)
			(effects
				(font
					(size 1 1)
					(thickness 0.15)
				)
				(justify mirror)
			)
		)
		(property "dnp" ""
			(at 109.5 294.9 0)
			(layer "B.Fab")
			(hide yes)
			(effects
				(font
					(size 1 1)
					(thickness 0.15)
				)
				(justify mirror)
			)
		)
		(property "exclude_from_bom" ""
			(at 109.5 294.9 0)
			(layer "B.Fab")
			(hide yes)
			(effects
				(font
					(size 1 1)
					(thickness 0.15)
				)
				(justify mirror)
			)
		)
		(sheetname "HDMI + Ethernet")
		(sheetfile "hdmi-ethernet.kicad_sch")
		(attr smd exclude_from_bom)
		(fp_rect
			(start -0.925 0.47)
			(end 0.925 -0.47)
			(stroke
				(width 0.05)
				(type default)
			)
			(fill no)
			(layer "B.CrtYd")
		)
		(fp_rect
			(start -0.5 0.25)
			(end 0.5 -0.25)
			(stroke
				(width 0.15)
				(type solid)
			)
			(fill no)
			(layer "B.Fab")
		)
		(pad "1" smd roundrect
			(at -0.48 0 270)
			(size 0.59 0.64)
			(layers "B.Cu" "B.Mask" "B.Paste")
			(roundrect_rratio 0.25)
			(net 851 "/HDMI + Ethernet/GBE_LED_LINK-")
			(pintype "passive")
		)
		(pad "2" smd roundrect
			(at 0.48 0 270)
			(size 0.59 0.64)
			(layers "B.Cu" "B.Mask" "B.Paste")
			(roundrect_rratio 0.25)
			(net 1 "GND")
			(pintype "passive")
		)
	)
	(footprint "antmicro-footprints:R_0402_1005Metric"
		(layer "B.Cu")
		(at 191.9 79.8 90)
		(descr "Resistor SMD 0402")
		(tags "resistor SMD 0402")
		(property "Reference" "R146"
			(at -0.725 0.4 270)
			(layer "B.SilkS")
			(effects
				(font
					(size 0.7 0.7)
					(thickness 0.15)
				)
				(justify left bottom mirror)
			)
		)
		(property "Value" "R_100R_0402"
			(at 0 -1.4 270)
			(layer "B.Fab")
			(effects
				(font
					(size 0.7 0.7)
					(thickness 0.15)
				)
				(justify left bottom mirror)
			)
		)
		(property "Description" "SMD Chip Resistor, 100 ohm, ± 1%, 62.5 mW, 0402 [1005 Metric], Thick Film, General Purpose"
			(at 0 0 90)
			(layer "F.Fab")
			(hide yes)
			(effects
				(font
					(size 1.27 1.27)
					(thickness 0.15)
				)
			)
		)
		(property "Author" "Antmicro"
			(at 271.7 -112.1 0)
			(layer "B.Fab")
			(hide yes)
			(effects
				(font
					(size 1 1)
					(thickness 0.15)
				)
				(justify mirror)
			)
		)
		(property "License" "Apache-2.0"
			(at 271.7 -112.1 0)
			(layer "B.Fab")
			(hide yes)
			(effects
				(font
					(size 1 1)
					(thickness 0.15)
				)
				(justify mirror)
			)
		)
		(property "MPN" "CR0402-FX-1000GLF"
			(at 271.7 -112.1 0)
			(layer "B.Fab")
			(hide yes)
			(effects
				(font
					(size 1 1)
					(thickness 0.15)
				)
				(justify mirror)
			)
		)
		(property "Manufacturer" "Bourns"
			(at 271.7 -112.1 0)
			(layer "B.Fab")
			(hide yes)
			(effects
				(font
					(size 1 1)
					(thickness 0.15)
				)
				(justify mirror)
			)
		)
		(property "Tolerance" "1%"
			(at 271.7 -112.1 0)
			(layer "B.Fab")
			(hide yes)
			(effects
				(font
					(size 1 1)
					(thickness 0.15)
				)
				(justify mirror)
			)
		)
		(property "Val" "100R"
			(at 271.7 -112.1 0)
			(layer "B.Fab")
			(hide yes)
			(effects
				(font
					(size 1 1)
					(thickness 0.15)
				)
				(justify mirror)
			)
		)
		(sheetname "User GPIO + LED + button + DIP switch")
		(sheetfile "user-gpio.kicad_sch")
		(attr smd)
		(fp_rect
			(start -0.925 0.47)
			(end 0.925 -0.47)
			(stroke
				(width 0.05)
				(type default)
			)
			(fill no)
			(layer "B.CrtYd")
		)
		(fp_rect
			(start -0.5 0.25)
			(end 0.5 -0.25)
			(stroke
				(width 0.15)
				(type solid)
			)
			(fill no)
			(layer "B.Fab")
		)
		(pad "1" smd roundrect
			(at -0.48 0 90)
			(size 0.59 0.64)
			(layers "B.Cu" "B.Mask" "B.Paste")
			(roundrect_rratio 0.25)
			(net 492 "/FPGA Bank 12 & 13/CW_HEADER.IO3")
			(pintype "passive")
		)
		(pad "2" smd roundrect
			(at 0.48 0 90)
			(size 0.59 0.64)
			(layers "B.Cu" "B.Mask" "B.Paste")
			(roundrect_rratio 0.25)
			(net 831 "/User GPIO + LED + button + DIP switch/CW_20PIN_IO3")
			(pintype "passive")
		)
	)
	(footprint "antmicro-footprints:C_0603_1608Metric"
		(layer "B.Cu")
		(at 200 147 90)
		(descr "Capacitor SMD 0603")
		(tags "capacitor 0603")
		(property "Reference" "C387"
			(at -3.85 0.375 90)
			(layer "B.SilkS")
			(effects
				(font
					(size 0.7 0.7)
					(thickness 0.15)
				)
				(justify right bottom mirror)
			)
		)
		(property "Value" "C_47u_0603"
			(at 0 -1.6 90)
			(layer "B.Fab")
			(effects
				(font
					(size 0.7 0.7)
					(thickness 0.15)
				)
				(justify right bottom mirror)
			)
		)
		(property "Description" "SMD Multilayer Ceramic Capacitor, 47 µF, 6.3 V, 0603 [1608 Metric], ± 20%, X5R, GRM Series"
			(at 0 0 90)
			(layer "F.Fab")
			(hide yes)
			(effects
				(font
					(size 1.27 1.27)
					(thickness 0.15)
				)
			)
		)
		(property "Author" "Antmicro"
			(at 347 -53 0)
			(layer "B.Fab")
			(hide yes)
			(effects
				(font
					(size 1 1)
					(thickness 0.15)
				)
				(justify mirror)
			)
		)
		(property "Dielectric" ""
			(at 347 -53 0)
			(layer "B.Fab")
			(hide yes)
			(effects
				(font
					(size 1 1)
					(thickness 0.15)
				)
				(justify mirror)
			)
		)
		(property "License" "Apache-2.0"
			(at 347 -53 0)
			(layer "B.Fab")
			(hide yes)
			(effects
				(font
					(size 1 1)
					(thickness 0.15)
				)
				(justify mirror)
			)
		)
		(property "MPN" "GRM188R60J476ME15D"
			(at 347 -53 0)
			(layer "B.Fab")
			(hide yes)
			(effects
				(font
					(size 1 1)
					(thickness 0.15)
				)
				(justify mirror)
			)
		)
		(property "Manufacturer" "Murata"
			(at 347 -53 0)
			(layer "B.Fab")
			(hide yes)
			(effects
				(font
					(size 1 1)
					(thickness 0.15)
				)
				(justify mirror)
			)
		)
		(property "Val" "47u"
			(at 347 -53 0)
			(layer "B.Fab")
			(hide yes)
			(effects
				(font
					(size 1 1)
					(thickness 0.15)
				)
				(justify mirror)
			)
		)
		(property "Voltage" ""
			(at 347 -53 0)
			(layer "B.Fab")
			(hide yes)
			(effects
				(font
					(size 1 1)
					(thickness 0.15)
				)
				(justify mirror)
			)
		)
		(sheetname "FPGA supply")
		(sheetfile "fpga-supply.kicad_sch")
		(attr smd)
		(fp_line
			(start -0.15 -0.4)
			(end 0.15 -0.4)
			(stroke
				(width 0.15)
				(type solid)
			)
			(layer "B.SilkS")
		)
		(fp_line
			(start -0.15 0.4)
			(end 0.15 0.4)
			(stroke
				(width 0.15)
				(type solid)
			)
			(layer "B.SilkS")
		)
		(fp_rect
			(start -1.25 0.65)
			(end 1.25 -0.65)
			(stroke
				(width 0.05)
				(type solid)
			)
			(fill no)
			(layer "B.CrtYd")
		)
		(fp_rect
			(start -0.8 0.4)
			(end 0.8 -0.4)
			(stroke
				(width 0.15)
				(type solid)
			)
			(fill no)
			(layer "B.Fab")
		)
		(pad "1" smd roundrect
			(at -0.7 0 90)
			(size 0.8 1)
			(layers "B.Cu" "B.Mask" "B.Paste")
			(roundrect_rratio 0.2)
			(net 1 "GND")
			(pintype "passive")
		)
		(pad "2" smd roundrect
			(at 0.7 0 90)
			(size 0.8 1)
			(layers "B.Cu" "B.Mask" "B.Paste")
			(roundrect_rratio 0.2)
			(net 650 "+1V0")
			(pintype "passive")
		)
	)
)
